(kicad_pcb
	(version 20241229)
	(generator "pcbnew")
	(generator_version "9.0")
	(general
		(thickness 1.62)
		(legacy_teardrops no)
	)
	(paper "A3")
	(title_block
		(title "COM Express 7 Baseboard")
		(date "2025-02-04")
		(rev "1.1.2")
		(company "Antmicro Ltd")
		(comment 1 "www.antmicro.com")
		(comment 9 "footprints 102-106 of 802")
	)
	(layers
		(0 "F.Cu" signal)
		(4 "In1.Cu" signal)
		(6 "In2.Cu" signal)
		(8 "In3.Cu" signal)
		(10 "In4.Cu" signal)
		(12 "In5.Cu" signal)
		(14 "In6.Cu" signal)
		(2 "B.Cu" signal)
		(9 "F.Adhes" user "F.Adhesive")
		(11 "B.Adhes" user "B.Adhesive")
		(13 "F.Paste" user)
		(15 "B.Paste" user)
		(5 "F.SilkS" user "F.Silkscreen")
		(7 "B.SilkS" user "B.Silkscreen")
		(1 "F.Mask" user)
		(3 "B.Mask" user)
		(17 "Dwgs.User" user "User.Drawings")
		(19 "Cmts.User" user "User.Comments")
		(21 "Eco1.User" user "User.Eco1")
		(23 "Eco2.User" user "User.Eco2")
		(25 "Edge.Cuts" user)
		(27 "Margin" user)
		(31 "F.CrtYd" user "F.Courtyard")
		(29 "B.CrtYd" user "B.Courtyard")
		(35 "F.Fab" user)
		(33 "B.Fab" user)
	)
	(footprint "antmicro-footprints:Conn_Molex_KK_1x4_0470531000"
		(layer "F.Cu")
		(at 252.510709 71.86 180)
		(property "Reference" "J10"
			(at 7.240001 -3.85 0)
			(layer "F.SilkS")
			(effects
				(font
					(size 0.7 0.7)
					(thickness 0.15)
				)
				(justify right bottom)
			)
		)
		(property "Value" "Molex_KK_1x4_0470531000"
			(at 0 4.7 0)
			(layer "F.Fab")
			(effects
				(font
					(size 0.7 0.7)
					(thickness 0.15)
				)
				(justify right bottom)
			)
		)
		(property "Datasheet" "https://tools.molex.com/pdm_docs/sd/470531000_sd.pdf"
			(at 0 0 180)
			(layer "F.Fab")
			(hide yes)
			(effects
				(font
					(size 1.27 1.27)
					(thickness 0.15)
				)
			)
		)
		(property "Author" "Antmicro"
			(at 505.021418 143.72 0)
			(layer "F.Fab")
			(hide yes)
			(effects
				(font
					(size 1 1)
					(thickness 0.15)
				)
			)
		)
		(property "License" "Apache-2.0"
			(at 505.021418 143.72 0)
			(layer "F.Fab")
			(hide yes)
			(effects
				(font
					(size 1 1)
					(thickness 0.15)
				)
			)
		)
		(property "MPN" "0470531000"
			(at 505.021418 143.72 0)
			(layer "F.Fab")
			(hide yes)
			(effects
				(font
					(size 1 1)
					(thickness 0.15)
				)
			)
		)
		(property "Manufacturer" "Molex"
			(at 505.021418 143.72 0)
			(layer "F.Fab")
			(hide yes)
			(effects
				(font
					(size 1 1)
					(thickness 0.15)
				)
			)
		)
		(sheetname "Misc")
		(sheetfile "misc.kicad_sch")
		(attr through_hole)
		(fp_line
			(start 8.95 3.4)
			(end -1.35 3.4)
			(stroke
				(width 0.15)
				(type solid)
			)
			(layer "F.SilkS")
		)
		(fp_line
			(start 8.95 -2.55)
			(end 8.95 3.4)
			(stroke
				(width 0.15)
				(type solid)
			)
			(layer "F.SilkS")
		)
		(fp_line
			(start 5.75 -2.55)
			(end 8.95 -2.55)
			(stroke
				(width 0.15)
				(type solid)
			)
			(layer "F.SilkS")
		)
		(fp_line
			(start 5.08 2.29)
			(end 5.08 3.3)
			(stroke
				(width 0.15)
				(type solid)
			)
			(layer "F.SilkS")
		)
		(fp_line
			(start 0 3.3)
			(end 0 2.29)
			(stroke
				(width 0.15)
				(type solid)
			)
			(layer "F.SilkS")
		)
		(fp_line
			(start 0 2.29)
			(end 5.08 2.29)
			(stroke
				(width 0.15)
				(type solid)
			)
			(layer "F.SilkS")
		)
		(fp_line
			(start -1.35 3.4)
			(end -1.35 -2.6)
			(stroke
				(width 0.15)
				(type solid)
			)
			(layer "F.SilkS")
		)
		(fp_line
			(start -1.35 -2.6)
			(end 4.4 -2.6)
			(stroke
				(width 0.15)
				(type solid)
			)
			(layer "F.SilkS")
		)
		(fp_circle
			(center 0 -3)
			(end 0.05 -3)
			(stroke
				(width 0.15)
				(type solid)
			)
			(fill yes)
			(layer "F.SilkS")
		)
		(fp_rect
			(start -1.54 -2.96)
			(end 9.16 3.55)
			(stroke
				(width 0.05)
				(type solid)
			)
			(fill no)
			(layer "F.CrtYd")
		)
		(fp_line
			(start 8.85 3.3)
			(end -1.2 3.3)
			(stroke
				(width 0.15)
				(type solid)
			)
			(layer "F.Fab")
		)
		(fp_line
			(start 8.85 -2.5)
			(end 8.85 3.3)
			(stroke
				(width 0.15)
				(type solid)
			)
			(layer "F.Fab")
		)
		(fp_line
			(start 5.75 -2.5)
			(end 8.85 -2.5)
			(stroke
				(width 0.15)
				(type solid)
			)
			(layer "F.Fab")
		)
		(fp_line
			(start 5.1 3.3)
			(end 5.1 2.3)
			(stroke
				(width 0.15)
				(type solid)
			)
			(layer "F.Fab")
		)
		(fp_line
			(start 5.1 2.3)
			(end 0 2.3)
			(stroke
				(width 0.15)
				(type solid)
			)
			(layer "F.Fab")
		)
		(fp_line
			(start 0 2.3)
			(end 0 3.3)
			(stroke
				(width 0.15)
				(type solid)
			)
			(layer "F.Fab")
		)
		(fp_line
			(start -1.2 3.3)
			(end -1.25 3.3)
			(stroke
				(width 0.15)
				(type solid)
			)
			(layer "F.Fab")
		)
		(fp_line
			(start -1.25 3.3)
			(end -1.25 -2.5)
			(stroke
				(width 0.15)
				(type solid)
			)
			(layer "F.Fab")
		)
		(fp_line
			(start -1.25 -2.5)
			(end 4.4 -2.5)
			(stroke
				(width 0.15)
				(type solid)
			)
			(layer "F.Fab")
		)
		(pad "" np_thru_hole circle
			(at 5.08 -2.16 270)
			(size 1.1 1.1)
			(drill 1.1)
			(layers "*.Cu" "*.Mask")
		)
		(pad "1" thru_hole rect
			(at 0 0 270)
			(size 2.03 1.73)
			(drill 1.02)
			(layers "*.Cu" "*.Mask")
			(remove_unused_layers no)
			(net 1 "GND")
			(pintype "passive")
			(teardrops
				(best_length_ratio 0.2)
				(max_length 1)
				(best_width_ratio 0.9)
				(max_width 2)
				(curved_edges yes)
				(filter_ratio 0.9)
				(enabled yes)
				(allow_two_segments yes)
				(prefer_zone_connections yes)
			)
		)
		(pad "2" thru_hole oval
			(at 2.54 0 270)
			(size 2.03 1.73)
			(drill 1.02)
			(layers "*.Cu" "*.Mask")
			(remove_unused_layers no)
			(net 81 "/Misc/FAN_12V")
			(pintype "passive")
			(teardrops
				(best_length_ratio 0.2)
				(max_length 1)
				(best_width_ratio 0.9)
				(max_width 2)
				(curved_edges yes)
				(filter_ratio 0.9)
				(enabled yes)
				(allow_two_segments yes)
				(prefer_zone_connections yes)
			)
		)
		(pad "3" thru_hole oval
			(at 5.08 0 270)
			(size 2.03 1.73)
			(drill 1.02)
			(layers "*.Cu" "*.Mask")
			(remove_unused_layers no)
			(net 281 "/Misc/TACH_{B5V}")
			(pintype "passive")
			(teardrops
				(best_length_ratio 0.2)
				(max_length 1)
				(best_width_ratio 0.9)
				(max_width 2)
				(curved_edges yes)
				(filter_ratio 0.9)
				(enabled yes)
				(allow_two_segments yes)
				(prefer_zone_connections yes)
			)
		)
		(pad "4" thru_hole oval
			(at 7.62 0 270)
			(size 2.03 1.73)
			(drill 1.02)
			(layers "*.Cu" "*.Mask")
			(remove_unused_layers no)
			(net 282 "/Misc/PWM_{B5V}")
			(pintype "passive")
			(teardrops
				(best_length_ratio 0.2)
				(max_length 1)
				(best_width_ratio 0.9)
				(max_width 2)
				(curved_edges yes)
				(filter_ratio 0.9)
				(enabled yes)
				(allow_two_segments yes)
				(prefer_zone_connections yes)
			)
		)
	)
	(footprint "antmicro-footprints:R_0402_1005Metric"
		(layer "F.Cu")
		(at 158.55 156.81 -90)
		(descr "Resistor SMD 0402")
		(tags "resistor SMD 0402")
		(property "Reference" "R36"
			(at -3.013 -0.449 90)
			(layer "F.SilkS")
			(effects
				(font
					(size 0.7 0.7)
					(thickness 0.15)
				)
				(justify right bottom)
			)
		)
		(property "Value" "R_0R_0402"
			(at -1.011843 1.772047 90)
			(layer "F.Fab")
			(effects
				(font
					(size 0.7 0.7)
					(thickness 0.15)
				)
				(justify right bottom)
			)
		)
		(property "Datasheet" "https://industrial.panasonic.com/cdbs/www-data/pdf/RDA0000/AOA0000C301.pdf"
			(at 0 0 270)
			(layer "F.Fab")
			(hide yes)
			(effects
				(font
					(size 1.27 1.27)
					(thickness 0.15)
				)
			)
		)
		(property "Author" "Antmicro"
			(at 1.74 315.36 0)
			(layer "F.Fab")
			(hide yes)
			(effects
				(font
					(size 1 1)
					(thickness 0.15)
				)
			)
		)
		(property "Current" "1A"
			(at 1.74 315.36 0)
			(layer "F.Fab")
			(hide yes)
			(effects
				(font
					(size 1 1)
					(thickness 0.15)
				)
			)
		)
		(property "License" "Apache-2.0"
			(at 1.74 315.36 0)
			(layer "F.Fab")
			(hide yes)
			(effects
				(font
					(size 1 1)
					(thickness 0.15)
				)
			)
		)
		(property "MPN" "ERJ2GE0R00X"
			(at 1.74 315.36 0)
			(layer "F.Fab")
			(hide yes)
			(effects
				(font
					(size 1 1)
					(thickness 0.15)
				)
			)
		)
		(property "Manufacturer" "Panasonic"
			(at 1.74 315.36 0)
			(layer "F.Fab")
			(hide yes)
			(effects
				(font
					(size 1 1)
					(thickness 0.15)
				)
			)
		)
		(property "Public" "False"
			(at 1.74 315.36 0)
			(layer "F.Fab")
			(hide yes)
			(effects
				(font
					(size 1 1)
					(thickness 0.15)
				)
			)
		)
		(property "Tolerance" ""
			(at 1.74 315.36 0)
			(layer "F.Fab")
			(hide yes)
			(effects
				(font
					(size 1 1)
					(thickness 0.15)
				)
			)
		)
		(property "Val" "0R"
			(at 1.74 315.36 0)
			(layer "F.Fab")
			(hide yes)
			(effects
				(font
					(size 1 1)
					(thickness 0.15)
				)
			)
		)
		(sheetname "2xSFP+")
		(sheetfile "2xSFP+.kicad_sch")
		(attr smd)
		(fp_rect
			(start -0.925 -0.47)
			(end 0.925 0.47)
			(stroke
				(width 0.05)
				(type default)
			)
			(fill no)
			(layer "F.CrtYd")
		)
		(fp_rect
			(start -0.5 -0.25)
			(end 0.5 0.25)
			(stroke
				(width 0.15)
				(type solid)
			)
			(fill no)
			(layer "F.Fab")
		)
		(pad "1" smd roundrect
			(at -0.48 0 270)
			(size 0.59 0.64)
			(layers "F.Cu" "F.Mask" "F.Paste")
			(roundrect_rratio 0.25)
			(net 1 "GND")
			(pintype "passive")
			(teardrops
				(best_length_ratio 0.2)
				(max_length 1)
				(best_width_ratio 0.9)
				(max_width 2)
				(curved_edges yes)
				(filter_ratio 0.9)
				(enabled yes)
				(allow_two_segments yes)
				(prefer_zone_connections yes)
			)
		)
		(pad "2" smd roundrect
			(at 0.48 0 270)
			(size 0.59 0.64)
			(layers "F.Cu" "F.Mask" "F.Paste")
			(roundrect_rratio 0.25)
			(net 561 "Net-(U5-A1)")
			(pintype "passive")
			(teardrops
				(best_length_ratio 0.2)
				(max_length 1)
				(best_width_ratio 0.9)
				(max_width 2)
				(curved_edges yes)
				(filter_ratio 0.9)
				(enabled yes)
				(allow_two_segments yes)
				(prefer_zone_connections yes)
			)
		)
	)
	(footprint "antmicro-footprints:R_0402_1005Metric"
		(layer "F.Cu")
		(at 215.925 136.95 -90)
		(descr "Resistor SMD 0402")
		(tags "resistor SMD 0402")
		(property "Reference" "R184"
			(at 0.86 -0.475 90)
			(layer "F.SilkS")
			(effects
				(font
					(size 0.7 0.7)
					(thickness 0.15)
				)
				(justify right bottom)
			)
		)
		(property "Value" "R_1k_0402"
			(at -1.011843 1.772047 90)
			(layer "F.Fab")
			(effects
				(font
					(size 0.7 0.7)
					(thickness 0.15)
				)
				(justify right bottom)
			)
		)
		(property "Datasheet" "https://www.bourns.com/docs/product-datasheets/cr.pdf"
			(at 0 0 270)
			(layer "F.Fab")
			(hide yes)
			(effects
				(font
					(size 1.27 1.27)
					(thickness 0.15)
				)
			)
		)
		(property "Author" "Antmicro"
			(at 78.975 352.875 0)
			(layer "F.Fab")
			(hide yes)
			(effects
				(font
					(size 1 1)
					(thickness 0.15)
				)
			)
		)
		(property "License" "Apache-2.0"
			(at 78.975 352.875 0)
			(layer "F.Fab")
			(hide yes)
			(effects
				(font
					(size 1 1)
					(thickness 0.15)
				)
			)
		)
		(property "MPN" "CR0402-FX-1001GLF"
			(at 78.975 352.875 0)
			(layer "F.Fab")
			(hide yes)
			(effects
				(font
					(size 1 1)
					(thickness 0.15)
				)
			)
		)
		(property "Manufacturer" "Bourns"
			(at 78.975 352.875 0)
			(layer "F.Fab")
			(hide yes)
			(effects
				(font
					(size 1 1)
					(thickness 0.15)
				)
			)
		)
		(property "Public" "False"
			(at 78.975 352.875 0)
			(layer "F.Fab")
			(hide yes)
			(effects
				(font
					(size 1 1)
					(thickness 0.15)
				)
			)
		)
		(property "Tolerance" "1%"
			(at 78.975 352.875 0)
			(layer "F.Fab")
			(hide yes)
			(effects
				(font
					(size 1 1)
					(thickness 0.15)
				)
			)
		)
		(property "Val" "1k"
			(at 78.975 352.875 0)
			(layer "F.Fab")
			(hide yes)
			(effects
				(font
					(size 1 1)
					(thickness 0.15)
				)
			)
		)
		(sheetname "PCIe misc")
		(sheetfile "pcie_misc.kicad_sch")
		(attr smd)
		(fp_rect
			(start -0.925 -0.47)
			(end 0.925 0.47)
			(stroke
				(width 0.05)
				(type default)
			)
			(fill no)
			(layer "F.CrtYd")
		)
		(fp_rect
			(start -0.5 -0.25)
			(end 0.5 0.25)
			(stroke
				(width 0.15)
				(type solid)
			)
			(fill no)
			(layer "F.Fab")
		)
		(pad "1" smd roundrect
			(at -0.48 0 270)
			(size 0.59 0.64)
			(layers "F.Cu" "F.Mask" "F.Paste")
			(roundrect_rratio 0.25)
			(net 604 "Net-(U37-~{OE2})")
			(pintype "passive")
			(teardrops
				(best_length_ratio 0.2)
				(max_length 1)
				(best_width_ratio 0.9)
				(max_width 2)
				(curved_edges yes)
				(filter_ratio 0.9)
				(enabled yes)
				(allow_two_segments yes)
				(prefer_zone_connections yes)
			)
		)
		(pad "2" smd roundrect
			(at 0.48 0 270)
			(size 0.59 0.64)
			(layers "F.Cu" "F.Mask" "F.Paste")
			(roundrect_rratio 0.25)
			(net 1 "GND")
			(pintype "passive")
			(teardrops
				(best_length_ratio 0.2)
				(max_length 1)
				(best_width_ratio 0.9)
				(max_width 2)
				(curved_edges yes)
				(filter_ratio 0.9)
				(enabled yes)
				(allow_two_segments yes)
				(prefer_zone_connections yes)
			)
		)
	)
	(footprint "antmicro-footprints:R_0201"
		(layer "F.Cu")
		(at 149.57 147.336 -90)
		(descr "Resistor SMD 0201")
		(tags "resistor SMD 0201")
		(property "Reference" "R273"
			(at 4.099 -0.33 270)
			(layer "F.SilkS")
			(effects
				(font
					(size 0.7 0.7)
					(thickness 0.15)
				)
				(justify left bottom)
			)
		)
		(property "Value" "R_0R_0201"
			(at 0 1.25 270)
			(layer "F.Fab")
			(effects
				(font
					(size 0.7 0.7)
					(thickness 0.15)
				)
				(justify left bottom)
			)
		)
		(property "Datasheet" "https://www.bourns.com/docs/product-datasheets/cr.pdf"
			(at 0 0 270)
			(layer "F.Fab")
			(hide yes)
			(effects
				(font
					(size 1.27 1.27)
					(thickness 0.15)
				)
			)
		)
		(property "Author" "Antmicro"
			(at 2.234 296.906 0)
			(layer "F.Fab")
			(hide yes)
			(effects
				(font
					(size 1 1)
					(thickness 0.15)
				)
			)
		)
		(property "License" "Apache-2.0"
			(at 2.234 296.906 0)
			(layer "F.Fab")
			(hide yes)
			(effects
				(font
					(size 1 1)
					(thickness 0.15)
				)
			)
		)
		(property "MPN" "CR0201-FX-0R00GLF"
			(at 2.234 296.906 0)
			(layer "F.Fab")
			(hide yes)
			(effects
				(font
					(size 1 1)
					(thickness 0.15)
				)
			)
		)
		(property "Manufacturer" "Bourns"
			(at 2.234 296.906 0)
			(layer "F.Fab")
			(hide yes)
			(effects
				(font
					(size 1 1)
					(thickness 0.15)
				)
			)
		)
		(property "Tolerance" "1%"
			(at 2.234 296.906 0)
			(layer "F.Fab")
			(hide yes)
			(effects
				(font
					(size 1 1)
					(thickness 0.15)
				)
			)
		)
		(property "Val" "0R"
			(at 2.234 296.906 0)
			(layer "F.Fab")
			(hide yes)
			(effects
				(font
					(size 1 1)
					(thickness 0.15)
				)
			)
		)
		(sheetname "KR to SFI #1")
		(sheetfile "kr_sfi.kicad_sch")
		(attr smd)
		(fp_rect
			(start -0.7 -0.35)
			(end 0.7 0.35)
			(stroke
				(width 0.05)
				(type default)
			)
			(fill no)
			(layer "F.CrtYd")
		)
		(fp_rect
			(start -0.3 -0.15)
			(end 0.298 0.148)
			(stroke
				(width 0.15)
				(type solid)
			)
			(fill no)
			(layer "F.Fab")
		)
		(pad "" smd roundrect
			(at -0.346 0 270)
			(size 0.318 0.36)
			(layers "F.Paste")
			(roundrect_rratio 0.25)
			(teardrops
				(best_length_ratio 0.2)
				(max_length 1)
				(best_width_ratio 0.9)
				(max_width 2)
				(curved_edges yes)
				(filter_ratio 0.9)
				(enabled yes)
				(allow_two_segments yes)
				(prefer_zone_connections yes)
			)
		)
		(pad "" smd roundrect
			(at 0.344 0 270)
			(size 0.318 0.36)
			(layers "F.Paste")
			(roundrect_rratio 0.25)
			(teardrops
				(best_length_ratio 0.2)
				(max_length 1)
				(best_width_ratio 0.9)
				(max_width 2)
				(curved_edges yes)
				(filter_ratio 0.9)
				(enabled yes)
				(allow_two_segments yes)
				(prefer_zone_connections yes)
			)
		)
		(pad "1" smd roundrect
			(at -0.32 0 270)
			(size 0.46 0.4)
			(layers "F.Cu" "F.Mask")
			(roundrect_rratio 0.25)
			(net 667 "/2xSFP+/KR to SFI #1/SFI_R.RX+")
			(pintype "passive")
			(teardrops
				(best_length_ratio 0.2)
				(max_length 1)
				(best_width_ratio 0.9)
				(max_width 2)
				(curved_edges yes)
				(filter_ratio 0.9)
				(enabled yes)
				(allow_two_segments yes)
				(prefer_zone_connections yes)
			)
		)
		(pad "2" smd roundrect
			(at 0.32 0 270)
			(size 0.46 0.4)
			(layers "F.Cu" "F.Mask")
			(roundrect_rratio 0.25)
			(net 171 "/2xSFP+/SFI0.RX+")
			(pintype "passive")
			(teardrops
				(best_length_ratio 0.2)
				(max_length 1)
				(best_width_ratio 0.9)
				(max_width 2)
				(curved_edges yes)
				(filter_ratio 0.9)
				(enabled yes)
				(allow_two_segments yes)
				(prefer_zone_connections yes)
			)
		)
	)
	(footprint "antmicro-footprints:L_WE-MAPI-4020"
		(layer "F.Cu")
		(at 311.240498 130.51 180)
		(property "Reference" "L4"
			(at -2.309502 1.45 0)
			(layer "F.SilkS")
			(effects
				(font
					(size 0.7 0.7)
					(thickness 0.15)
				)
				(justify left bottom)
			)
		)
		(property "Value" "L_1u8_6.8A_WE-MAPI-4020"
			(at -2.4 3.4 0)
			(layer "F.Fab")
			(effects
				(font
					(size 0.7 0.7)
					(thickness 0.15)
				)
				(justify left bottom)
			)
		)
		(property "Datasheet" "https://www.we-online.com/components/products/datasheet/74438356018.pdf"
			(at 0 0 180)
			(layer "F.Fab")
			(hide yes)
			(effects
				(font
					(size 1.27 1.27)
					(thickness 0.15)
				)
			)
		)
		(property "Author" "Antmicro"
			(at 622.480996 261.02 0)
			(layer "F.Fab")
			(hide yes)
			(effects
				(font
					(size 1 1)
					(thickness 0.15)
				)
			)
		)
		(property "IMax" "6.8 A"
			(at 622.480996 261.02 0)
			(layer "F.Fab")
			(hide yes)
			(effects
				(font
					(size 1 1)
					(thickness 0.15)
				)
			)
		)
		(property "ISat" "6.5 A"
			(at 622.480996 261.02 0)
			(layer "F.Fab")
			(hide yes)
			(effects
				(font
					(size 1 1)
					(thickness 0.15)
				)
			)
		)
		(property "License" "Apache-2.0"
			(at 622.480996 261.02 0)
			(layer "F.Fab")
			(hide yes)
			(effects
				(font
					(size 1 1)
					(thickness 0.15)
				)
			)
		)
		(property "MPN" "74438356018"
			(at 622.480996 261.02 0)
			(layer "F.Fab")
			(hide yes)
			(effects
				(font
					(size 1 1)
					(thickness 0.15)
				)
			)
		)
		(property "Manufacturer" "Würth Elektronik"
			(at 622.480996 261.02 0)
			(layer "F.Fab")
			(hide yes)
			(effects
				(font
					(size 1 1)
					(thickness 0.15)
				)
			)
		)
		(property "Public" "False"
			(at 622.480996 261.02 0)
			(layer "F.Fab")
			(hide yes)
			(effects
				(font
					(size 1 1)
					(thickness 0.15)
				)
			)
		)
		(property "Size" "4.1x4.1mm"
			(at 622.480996 261.02 0)
			(layer "F.Fab")
			(hide yes)
			(effects
				(font
					(size 1 1)
					(thickness 0.15)
				)
			)
		)
		(property "Val" "1u8/6.8A"
			(at 622.480996 261.02 0)
			(layer "F.Fab")
			(hide yes)
			(effects
				(font
					(size 1 1)
					(thickness 0.15)
				)
			)
		)
		(sheetname "Power")
		(sheetfile "power.kicad_sch")
		(attr smd)
		(fp_rect
			(start -2.2 -2.2)
			(end 2.2 2.2)
			(stroke
				(width 0.15)
				(type solid)
			)
			(fill no)
			(layer "F.SilkS")
		)
		(fp_rect
			(start -2.3 -2.3)
			(end 2.3 2.3)
			(stroke
				(width 0.05)
				(type solid)
			)
			(fill no)
			(layer "F.CrtYd")
		)
		(fp_rect
			(start -2.05 -2.05)
			(end 2.05 2.05)
			(stroke
				(width 0.15)
				(type solid)
			)
			(fill no)
			(layer "F.Fab")
		)
		(pad "1" smd roundrect
			(at -1.185 0 270)
			(size 3.7 1)
			(layers "F.Cu" "F.Mask" "F.Paste")
			(roundrect_rratio 0.1)
			(net 871 "Net-(U22-SW)")
			(pintype "passive")
			(teardrops
				(best_length_ratio 0.2)
				(max_length 1)
				(best_width_ratio 0.9)
				(max_width 2)
				(curved_edges yes)
				(filter_ratio 0.9)
				(enabled yes)
				(allow_two_segments yes)
				(prefer_zone_connections yes)
			)
		)
		(pad "2" smd roundrect
			(at 1.185 0 270)
			(size 3.7 1)
			(layers "F.Cu" "F.Mask" "F.Paste")
			(roundrect_rratio 0.1)
			(net 76 "Net-(C63-Pad2)")
			(pintype "passive")
			(teardrops
				(best_length_ratio 0.2)
				(max_length 1)
				(best_width_ratio 0.9)
				(max_width 2)
				(curved_edges yes)
				(filter_ratio 0.9)
				(enabled yes)
				(allow_two_segments yes)
				(prefer_zone_connections yes)
			)
		)
	)
)
